#ISCELL
  mstr_misc dns *
  *
#ISCELL
  mstr_symbols design_note *
  *
#ISCELL
  mstr_symbols intel_corp_bpage *
  *
#ISCELL
  mstr_standard offpage *
  page237_i1
#CELL
  mstr_discrete cap *
  page237_i12
#CELL
  mstr_discrete cap *
  page237_i13
#ISCELL
  mstr_symbols gnd *
  page237_i14
#CELL
  mstr_discrete res *
  page237_i15
#CELL
  mstr_discrete cap *
  page237_i29
#CELL
  mstr_discrete res *
  page237_i3
#ISCELL
  mstr_symbols gnd *
  page237_i30
#CELL
  mstr_discrete cap *
  page237_i31
#ISCELL
  mstr_symbols gnd *
  page237_i32
#ISCELL
  mstr_symbols p1v8_pch_stby *
  page237_i4
#CELL
  mstr_discrete cap *
  page237_i5
#CELL
  mstr_discrete cap *
  page237_i55
#ISCELL
  mstr_standard offpage *
  page237_i58
#ISCELL
  mstr_symbols gnd *
  page237_i6
#ISCELL
  mstr_symbols p3v3_stby *
  page237_i65
#ISCELL
  mstr_symbols gnd *
  page237_i71
#CELL
  mstr_discrete cap *
  page237_i77
#CELL
  mstr_discrete cap *
  page237_i79
#CELL
  mstr_discrete res *
  page237_i80
#CELL
  mstr_discrete res *
  page237_i81
#ISCELL
  mstr_symbols p3v3_stby *
  page237_i85
#CELL
  mstr_vreg rt9059 *
  page237_i86
#CELL
  mstr_discrete res *
  page237_i90
#ISCELL
  mstr_symbols gnd *
  page237_i91
#ISCELL
  mstr_symbols gnd *
  page237_i92
